FILE_TYPE = CONNECTIVITY;
{Allegro Design Entry HDL 17.4-2019 S026 (4007227) 1/17/2022}
"PAGE_NUMBER" = 187;
0"NC";
1"GND\g";
2"GND\g";
3"GND\g";
4"GND\g";
5"GND\g";
6"GND\g";
7"GND\g";
8"GND\g";
9"GND\g";
10"GND\g";
11"SW_P12V_AUX_PVDDCR_CPU0_P1_FLT\g";
12"GND\g";
13"PVDDCR_CPU0_P1_VOS3";
14"SW_PVDDCR_CPU0_P1_SW3";
15"SW_PVDDCR_CPU0_P1_PH3";
16"SW_PVDDCR_CPU0_P1_BOOT3";
17"SW_PVDDCR_CPU0_P1_BOOT3_RC";
18"SW_PVDDCR_CPU0_P1_BOOT4";
19"SW_PVDDCR_CPU0_P1_BOOT4_RC";
20"PVDDCR_CPU0_P1_PVCC\g";
21"GND\g";
22"PVDDCR_CPU0_P1_PVCC\g";
23"GND\g";
24"GND\g";
25"GND\g";
26"PVDDCR_CPU0_P1\g";
27"GND\g";
28"SW_P12V_AUX_PVDDCR_CPU0_P1_FLT\g";
29"GND\g";
30"PVDDCR_CPU0_P1\g";
31"SW_PVDDCR_CPU0_P1_PH4";
32"SW_PVDDCR_CPU0_P1_SW4";
33"IND_CPU0_P1_CPL3";
34"IND_CPU0_P1_CPL2";
35"IND_CPU0_P1_CPL3";
36"SW_PVDDCR_CPU0_P1_SW3_RC";
37"NC_PVDDCR_CPU0_P1_GL1_3";
38"NC_PVDDCR_CPU0_P1_GL2_3";
39"PVDDCR_CPU0_P1_VCC3";
40"PVDDCR_CPU0_P1_IMON3";
41"PVDDCR_CPU0_P1_TEMP0";
42"PVDDCR_CPU0_P1_PWM3";
43"NC_PVDDCR_CPU0_P1_DNC3";
44"PVDDCR_CPU0_P1_LSET3";
45"PVDDCR_CPU0_P1_VCCS";
46"SW_PVDDCR_CPU0_P1_SW4_RC";
47"PVDDCR_CPU0_P1_VOS4";
48"NC_PVDDCR_CPU0_P1_GL2_4";
49"NC_PVDDCR_CPU0_P1_GL1_4";
50"PVDDCR_CPU0_P1_VCC4";
51"PVDDCR_CPU0_P1_TEMP0";
52"PVDDCR_CPU0_P1_LSET4";
53"NC_PVDDCR_CPU0_P1_DNC4";
54"PVDDCR_CPU0_P1_IMON4";
55"PVDDCR_CPU0_P1_PWM4";
56"PVDDCR_CPU0_P1_VCCS";
%"Q_RES"
"1","(-6850,1275)","0","pure_quanta","I11";
;
LOCATION"PR196"
$SEC"1"
CDS_SEC"1"
PACK_TYPE"0402LF"
MATERIAL"EMPTY"
WATTAGE"1/16W"
TOLERANCE"1%"
VALUE"8.87K"
CDS_LIB"pure_quanta"
PART_NUMBER"CS28872FB01";
"B"
$PN"2"52;
"A"
$PN"1"8;
%"Q_RES"
"2","(-7150,2475)","0","pure_quanta","I12";
;
LOCATION"PR194"
$SEC"1"
CDS_SEC"1"
PACK_TYPE"0402LF"
VALUE"2.2"
TOLERANCE"1%"
MATERIAL"CHIP"
WATTAGE"1/16W"
CDS_LIB"pure_quanta"
PART_NUMBER"CS-2202FB01";
"A"
$PN"1"20;
"B"
$PN"2"50;
%"VCC_CORE"
"1","(-7150,2875)","0","pure_quanta_power","I13";
;
HDL_POWER"PVDDCR_CPU0_P1_PVCC"
CDS_LIB"pure_quanta_power";
"A"20;
%"UNIVERSAL_GND"
"1","(-6800,2225)","0","pure_quanta_power","I14";
;
CDS_LIB"pure_quanta_power"
HDL_POWER"GND";
"A"1;
%"Q_CAP"
"1","(-6800,2500)","0","pure_quanta","I15";
;
LOCATION"PC289_C0P1_4"
$SEC"1"
CDS_SEC"1"
PACK_TYPE"C0402"
VOLTAGE"10V"
VALUE"2.2UF"
MATERIAL"X6S"
TOLERANCE"10%"
CDS_LIB"pure_quanta"
PART_NUMBER"CH5222KEB01";
"B"
$PN"2"1;
"A"
$PN"1"20;
%"UNIVERSAL_GND"
"1","(-5125,825)","0","pure_quanta_power","I16";
;
CDS_LIB"pure_quanta_power"
HDL_POWER"GND";
"A"21;
%"Q_RES"
"1","(-3925,475)","0","pure_quanta","I17";
;
LOCATION"PR200"
$SEC"1"
CDS_SEC"1"
WATTAGE"1/16W"
MATERIAL"CHIP"
TOLERANCE"5%"
VALUE"0"
PACK_TYPE"0402LF"
CDS_LIB"pure_quanta"
PART_NUMBER"CS00002JB13";
"B"
$PN"2"26;
"A"
$PN"1"47;
%"UNIVERSAL_GND"
"1","(-4250,650)","0","pure_quanta_power","I18";
;
CDS_LIB"pure_quanta_power"
HDL_POWER"GND";
"A"2;
%"Q_RES"
"2","(-4250,875)","0","pure_quanta","I19";
;
LOCATION"PR523"
$SEC"1"
CDS_SEC"1"
PACK_TYPE"0402LF"
VALUE"1.5"
TOLERANCE"1%"
MATERIAL"EMPTY"
WATTAGE"1/8W"
CDS_LIB"pure_quanta"
PART_NUMBER"CS-1504FB00";
"A"
$PN"1"46;
"B"
$PN"2"2;
%"Q_CAP"
"1","(-7500,1300)","0","pure_quanta","I2";
;
LOCATION"PC285_4"
$SEC"1"
CDS_SEC"1"
PACK_TYPE"0402"
VOLTAGE"25V"
VALUE"0.1UF"
TOLERANCE"10%"
MATERIAL"X7R"
CDS_LIB"pure_quanta"
PART_NUMBER"CH4104K1B00";
"B"
$PN"2"5;
"A"
$PN"1"56;
%"Q_CAP"
"1","(-4250,1375)","0","pure_quanta","I20";
;
LOCATION"PC317"
$SEC"1"
CDS_SEC"1"
PACK_TYPE"C0402"
VOLTAGE"50V"
VALUE"560PF"
TOLERANCE"10%"
MATERIAL"EMPTY"
CDS_LIB"pure_quanta"
PART_NUMBER"CH1566K1B09";
"B"
$PN"2"46;
"A"
$PN"1"32;
%"Q_RES"
"1","(-4300,1925)","0","pure_quanta","I21";
;
LOCATION"PR198"
$SEC"1"
CDS_SEC"1"
TOLERANCE"1%"
PACK_TYPE"0402LF"
MATERIAL"CHIP"
WATTAGE"1/16W"
VALUE"5.6"
CDS_LIB"pure_quanta"
PART_NUMBER"CS-5602FB01";
"B"
$PN"2"19;
"A"
$PN"1"18;
%"Q_CAP"
"1","(-5000,2475)","0","pure_quanta","I22";
;
LOCATION"PC293_4"
$SEC"1"
CDS_SEC"1"
PACK_TYPE"0402"
VOLTAGE"25V"
VALUE"0.1UF"
TOLERANCE"10%"
MATERIAL"X7R"
CDS_LIB"pure_quanta"
PART_NUMBER"CH4104K1B00";
"B"
$PN"2"12;
"A"
$PN"1"11;
%"Q_CAP"
"1","(-4625,2475)","0","pure_quanta","I23";
;
LOCATION"PC291_4"
$SEC"1"
CDS_SEC"1"
TOLERANCE"10%"
VOLTAGE"25V"
VALUE"1UF"
MATERIAL"X6S"
PACK_TYPE"C0402"
CDS_LIB"pure_quanta"
PART_NUMBER"CH5104KEB02";
"B"
$PN"2"12;
"A"
$PN"1"11;
%"Q_CAP"
"1","(-4300,2475)","0","pure_quanta","I24";
;
LOCATION"PC295_4"
$SEC"1"
CDS_SEC"1"
PACK_TYPE"C0805"
VALUE"22UF"
MATERIAL"X6S"
VOLTAGE"16V"
TOLERANCE"20%"
CDS_LIB"pure_quanta"
PART_NUMBER"CH6223MEA01";
"B"
$PN"2"12;
"A"
$PN"1"11;
%"Q_CAP"
"1","(-3975,2475)","0","pure_quanta","I25";
;
LOCATION"PC297_4"
$SEC"1"
CDS_SEC"1"
MATERIAL"X6S"
TOLERANCE"20%"
VOLTAGE"16V"
VALUE"22UF"
PACK_TYPE"C0805"
CDS_LIB"pure_quanta"
PART_NUMBER"CH6223MEA01";
"B"
$PN"2"12;
"A"
$PN"1"11;
%"UNIVERSAL_GND"
"1","(-4250,3950)","0","pure_quanta_power","I26";
;
CDS_LIB"pure_quanta_power"
HDL_POWER"GND";
"A"3;
%"Q_RES"
"1","(-3975,3775)","0","pure_quanta","I27";
;
LOCATION"PR199"
$SEC"1"
CDS_SEC"1"
WATTAGE"1/16W"
MATERIAL"CHIP"
TOLERANCE"5%"
VALUE"0"
PACK_TYPE"0402LF"
CDS_LIB"pure_quanta"
PART_NUMBER"CS00002JB13";
"B"
$PN"2"30;
"A"
$PN"1"13;
%"Q_CAP"
"1","(-7575,4600)","0","pure_quanta","I28";
;
LOCATION"PC284_3"
$SEC"1"
CDS_SEC"1"
VOLTAGE"25V"
VALUE"0.1UF"
TOLERANCE"10%"
MATERIAL"X7R"
PACK_TYPE"0402"
CDS_LIB"pure_quanta"
PART_NUMBER"CH4104K1B00";
"B"
$PN"2"4;
"A"
$PN"1"45;
%"UNIVERSAL_GND"
"1","(-7575,4325)","0","pure_quanta_power","I29";
;
CDS_LIB"pure_quanta_power"
HDL_POWER"GND";
"A"4;
%"UNIVERSAL_GND"
"1","(-7500,1025)","0","pure_quanta_power","I3";
;
CDS_LIB"pure_quanta_power"
HDL_POWER"GND";
"A"5;
%"UNIVERSAL_GND"
"1","(-7275,4400)","0","pure_quanta_power","I31";
;
CDS_LIB"pure_quanta_power"
HDL_POWER"GND";
"A"6;
%"Q_RES"
"1","(-6950,4575)","0","pure_quanta","I34";
;
LOCATION"PR195"
$SEC"1"
CDS_SEC"1"
MATERIAL"EMPTY"
PACK_TYPE"0402LF"
WATTAGE"1/16W"
TOLERANCE"1%"
VALUE"8.87K"
CDS_LIB"pure_quanta"
PART_NUMBER"CS28872FB01";
"B"
$PN"2"44;
"A"
$PN"1"6;
%"UNIVERSAL_GND"
"1","(-7250,5025)","0","pure_quanta_power","I35";
;
CDS_LIB"pure_quanta_power"
HDL_POWER"GND";
"A"7;
%"Q_CAP"
"1","(-7250,5225)","0","pure_quanta","I37";
;
LOCATION"PC286"
$SEC"1"
CDS_SEC"1"
VOLTAGE"10V"
VALUE"2.2UF"
TOLERANCE"10%"
MATERIAL"X6S"
PACK_TYPE"C0402"
CDS_LIB"pure_quanta"
PART_NUMBER"CH5222KEB01";
"B"
$PN"2"7;
"A"
$PN"1"39;
%"Q_RES"
"2","(-7250,5775)","0","pure_quanta","I38";
;
LOCATION"PR193"
$SEC"1"
CDS_SEC"1"
MATERIAL"CHIP"
TOLERANCE"1%"
PACK_TYPE"0402LF"
WATTAGE"1/16W"
VALUE"2.2"
CDS_LIB"pure_quanta"
PART_NUMBER"CS-2202FB01";
"A"
$PN"1"22;
"B"
$PN"2"39;
%"ISL99390FRZTR5935"
"1","(-5750,4875)","0","pure_quanta","I39";
;
LOCATION"PU27"
$SEC"1"
CDS_SEC"1"
VALUE"ISL99390FRZ-TR5935"
MATERIAL"IC"
PART_TYPE"SMLF"
CDS_LMAN_SYM_OUTLINE"-300,700,250,-650"
NEEDS_NO_SIZE"TRUE"
CDS_LIB"pure_quanta"
PART_NUMBER"AL099390004";
"PGND2"
$PN"7_9-20_24"23;
"GL2"
$PN"41"38;
"GL1"
$PN"6"37;
"DNC"
$PN"31"43;
"EN"
$PN"35"39;
"PGND3"
$PN"40"23;
"VOS"
$PN"1"13;
"VIN2"
$PN"30"28;
"PGND1"
$PN"5"23;
"SW"
$PN"10_19"14;
"LSET"
$PN"37"44;
"IOUT"
$PN"38"40;
"TOUT_FLT"
$PN"36"41;
"PVCC"
$PN"4"22;
"PHASE"
$PN"32"15;
"VIN1"
$PN"25_29"28;
"BOOT"
$PN"33"16;
"AGND"
$PN"2"23;
"VCC"
$PN"3"39;
"REFIN"
$PN"39"45;
"PWM"
$PN"34"42;
%"UNIVERSAL_GND"
"1","(-7175,1100)","0","pure_quanta_power","I4";
;
CDS_LIB"pure_quanta_power"
HDL_POWER"GND";
"A"8;
%"UNIVERSAL_GND"
"1","(-6900,5525)","0","pure_quanta_power","I40";
;
CDS_LIB"pure_quanta_power"
HDL_POWER"GND";
"A"9;
%"Q_CAP"
"1","(-6900,5800)","0","pure_quanta","I41";
;
LOCATION"PC288_C0P1_3"
$SEC"1"
CDS_SEC"1"
TOLERANCE"10%"
MATERIAL"X6S"
VOLTAGE"10V"
PACK_TYPE"C0402"
VALUE"2.2UF"
CDS_LIB"pure_quanta"
PART_NUMBER"CH5222KEB01";
"B"
$PN"2"9;
"A"
$PN"1"22;
%"VCC_CORE"
"1","(-7250,6175)","0","pure_quanta_power","I42";
;
HDL_POWER"PVDDCR_CPU0_P1_PVCC"
CDS_LIB"pure_quanta_power";
"A"22;
%"UNIVERSAL_GND"
"1","(-5200,4100)","0","pure_quanta_power","I43";
;
CDS_LIB"pure_quanta_power"
HDL_POWER"GND";
"A"23;
%"Q_CAP"
"1","(-5125,5775)","0","pure_quanta","I44";
;
LOCATION"PC290_3"
$SEC"1"
CDS_SEC"1"
PACK_TYPE"0402"
VOLTAGE"25V"
VALUE"0.1UF"
TOLERANCE"10%"
MATERIAL"X7R"
CDS_LIB"pure_quanta"
PART_NUMBER"CH4104K1B00";
"B"
$PN"2"27;
"A"
$PN"1"28;
%"Q_RES"
"2","(-4250,4175)","0","pure_quanta","I45";
;
LOCATION"PR522"
$SEC"1"
CDS_SEC"1"
PACK_TYPE"0402LF"
VALUE"1.5"
TOLERANCE"1%"
MATERIAL"EMPTY"
WATTAGE"1/8W"
CDS_LIB"pure_quanta"
PART_NUMBER"CS-1504FB00";
"A"
$PN"1"36;
"B"
$PN"2"3;
%"Q_CAP"
"1","(-4250,4675)","0","pure_quanta","I46";
;
LOCATION"PC316"
$SEC"1"
CDS_SEC"1"
PACK_TYPE"C0402"
VOLTAGE"50V"
VALUE"560PF"
TOLERANCE"10%"
MATERIAL"EMPTY"
CDS_LIB"pure_quanta"
PART_NUMBER"CH1566K1B09";
"B"
$PN"2"36;
"A"
$PN"1"14;
%"Q_RES"
"1","(-4375,5225)","0","pure_quanta","I47";
;
LOCATION"PR197"
$SEC"1"
CDS_SEC"1"
MATERIAL"CHIP"
TOLERANCE"1%"
VALUE"5.6"
WATTAGE"1/16W"
PACK_TYPE"0402LF"
CDS_LIB"pure_quanta"
PART_NUMBER"CS-5602FB01";
"B"
$PN"2"17;
"A"
$PN"1"16;
%"Q_CAP"
"1","(-4775,5775)","0","pure_quanta","I48";
;
LOCATION"PC292_3"
$SEC"1"
CDS_SEC"1"
VOLTAGE"25V"
VALUE"1UF"
TOLERANCE"10%"
MATERIAL"X6S"
PACK_TYPE"C0402"
CDS_LIB"pure_quanta"
PART_NUMBER"CH5104KEB02";
"B"
$PN"2"27;
"A"
$PN"1"28;
%"Q_CAP"
"1","(-4450,5775)","0","pure_quanta","I49";
;
LOCATION"PC294_3"
$SEC"1"
CDS_SEC"1"
PACK_TYPE"C0805"
TOLERANCE"20%"
VOLTAGE"16V"
VALUE"22UF"
MATERIAL"X6S"
CDS_LIB"pure_quanta"
PART_NUMBER"CH6223MEA01";
"B"
$PN"2"27;
"A"
$PN"1"28;
%"UNIVERSAL_GND"
"1","(-7150,1725)","0","pure_quanta_power","I5";
;
CDS_LIB"pure_quanta_power"
HDL_POWER"GND";
"A"10;
%"Q_CAP"
"1","(-4125,5775)","0","pure_quanta","I50";
;
LOCATION"PC296_3"
$SEC"1"
CDS_SEC"1"
VALUE"22UF"
TOLERANCE"20%"
VOLTAGE"16V"
MATERIAL"X6S"
PACK_TYPE"C0805"
CDS_LIB"pure_quanta"
PART_NUMBER"CH6223MEA01";
"B"
$PN"2"27;
"A"
$PN"1"28;
%"Q_CAP"
"1","(-3325,1800)","0","pure_quanta","I52";
;
LOCATION"PC301"
$SEC"1"
CDS_SEC"1"
PACK_TYPE"0402"
VOLTAGE"16V"
VALUE"0.22UF"
TOLERANCE"10%"
MATERIAL"X7R"
CDS_LIB"pure_quanta"
PART_NUMBER"CH4223K1B00";
"B"
$PN"2"31;
"A"
$PN"1"19;
%"Q_INDUCTOR4P_14"
"1","(-2350,1450)","0","pure_quanta","I53";
;
LOCATION"PL32"
$SEC"1"
CDS_SEC"1"
VALUE"150NH"
MATERIAL"IND"
PART_TYPE"SMLF"
CDS_LIB"pure_quanta"
NEEDS_NO_SIZE"TRUE"
PART_NUMBER"CV+15^0TZ04";
"1"
$PN"1"32;
"4"
$PN"4"26;
"3"
$PN"3"24;
"2"
$PN"2"35;
%"UNIVERSAL_GND"
"1","(-3675,2125)","0","pure_quanta_power","I54";
;
CDS_LIB"pure_quanta_power"
HDL_POWER"GND";
"A"12;
%"Q_CAP"
"1","(-3675,2475)","0","pure_quanta","I55";
;
LOCATION"PC299_4"
$SEC"1"
CDS_SEC"1"
TOLERANCE"20%"
VOLTAGE"16V"
VALUE"22UF"
MATERIAL"X6S"
PACK_TYPE"C0805"
CDS_LIB"pure_quanta"
PART_NUMBER"CH6223MEA01";
"B"
$PN"2"12;
"A"
$PN"1"11;
%"VCC_CORE"
"1","(-3675,2775)","0","pure_quanta_power","I56";
;
HDL_POWER"SW_P12V_AUX_PVDDCR_CPU0_P1_FLT"
CDS_LIB"pure_quanta_power";
"A"11;
%"UNIVERSAL_GND"
"1","(-1525,1200)","0","pure_quanta_power","I57";
;
CDS_LIB"pure_quanta_power"
HDL_POWER"GND";
"A"24;
%"Q_CAP"
"1","(-1000,1400)","0","pure_quanta","I58";
;
LOCATION"PC303_4"
$SEC"1"
CDS_SEC"1"
PACK_TYPE"C0805"
MATERIAL"X6S"
TOLERANCE"20%"
VALUE"22UF"
VOLTAGE"4V"
CDS_LIB"pure_quanta"
PART_NUMBER"CH622KMEA03";
"B"
$PN"2"25;
"A"
$PN"1"26;
%"UNIVERSAL_GND"
"1","(-575,1050)","0","pure_quanta_power","I59";
;
CDS_LIB"pure_quanta_power"
HDL_POWER"GND";
"A"25;
%"Q_CAP"
"1","(-7150,1925)","0","pure_quanta","I6";
;
LOCATION"PC287"
$SEC"1"
CDS_SEC"1"
PACK_TYPE"C0402"
VOLTAGE"10V"
VALUE"2.2UF"
TOLERANCE"10%"
MATERIAL"X6S"
CDS_LIB"pure_quanta"
PART_NUMBER"CH5222KEB01";
"B"
$PN"2"10;
"A"
$PN"1"50;
%"Q_CAP"
"1","(-575,1400)","0","pure_quanta","I60";
;
LOCATION"PC305_4"
$SEC"1"
CDS_SEC"1"
PACK_TYPE"C0805"
MATERIAL"X6S"
TOLERANCE"20%"
VALUE"22UF"
VOLTAGE"4V"
CDS_LIB"pure_quanta"
PART_NUMBER"CH622KMEA03";
"B"
$PN"2"25;
"A"
$PN"1"26;
%"VCC_CORE"
"1","(-575,1725)","0","pure_quanta_power","I61";
;
HDL_POWER"PVDDCR_CPU0_P1"
CDS_LIB"pure_quanta_power";
"A"26;
%"Q_CAP"
"1","(-3400,5100)","0","pure_quanta","I63";
;
LOCATION"PC300"
$SEC"1"
CDS_SEC"1"
PACK_TYPE"0402"
MATERIAL"X7R"
TOLERANCE"10%"
VOLTAGE"16V"
VALUE"0.22UF"
CDS_LIB"pure_quanta"
PART_NUMBER"CH4223K1B00";
"B"
$PN"2"15;
"A"
$PN"1"17;
%"UNIVERSAL_GND"
"1","(-3825,5450)","0","pure_quanta_power","I64";
;
CDS_LIB"pure_quanta_power"
HDL_POWER"GND";
"A"27;
%"Q_CAP"
"1","(-3825,5775)","0","pure_quanta","I65";
;
LOCATION"PC298_3"
$SEC"1"
CDS_SEC"1"
TOLERANCE"20%"
VOLTAGE"16V"
VALUE"22UF"
MATERIAL"X6S"
PACK_TYPE"C0805"
CDS_LIB"pure_quanta"
PART_NUMBER"CH6223MEA01";
"B"
$PN"2"27;
"A"
$PN"1"28;
%"VCC_CORE"
"1","(-3825,6075)","0","pure_quanta_power","I66";
;
HDL_POWER"SW_P12V_AUX_PVDDCR_CPU0_P1_FLT"
CDS_LIB"pure_quanta_power";
"A"28;
%"Q_INDUCTOR4P_14"
"1","(-2450,4750)","0","pure_quanta","I67";
;
LOCATION"PL31"
$SEC"1"
CDS_SEC"1"
PART_TYPE"SMLF"
VALUE"150NH"
MATERIAL"IND"
NEEDS_NO_SIZE"TRUE"
CDS_LIB"pure_quanta"
PART_NUMBER"CV+15^0TZ04";
"1"
$PN"1"14;
"4"
$PN"4"30;
"3"
$PN"3"33;
"2"
$PN"2"34;
%"Q_CAP"
"1","(-1050,4700)","0","pure_quanta","I69";
;
LOCATION"PC302_3"
$SEC"1"
CDS_SEC"1"
PACK_TYPE"C0805"
MATERIAL"X6S"
TOLERANCE"20%"
VALUE"22UF"
VOLTAGE"4V"
CDS_LIB"pure_quanta"
PART_NUMBER"CH622KMEA03";
"B"
$PN"2"29;
"A"
$PN"1"30;
%"UNIVERSAL_GND"
"1","(-625,4350)","0","pure_quanta_power","I70";
;
CDS_LIB"pure_quanta_power"
HDL_POWER"GND";
"A"29;
%"Q_CAP"
"1","(-625,4700)","0","pure_quanta","I71";
;
LOCATION"PC304_3"
$SEC"1"
CDS_SEC"1"
PACK_TYPE"C0805"
MATERIAL"X6S"
TOLERANCE"20%"
VALUE"22UF"
VOLTAGE"4V"
CDS_LIB"pure_quanta"
PART_NUMBER"CH622KMEA03";
"B"
$PN"2"29;
"A"
$PN"1"30;
%"VCC_CORE"
"1","(-625,5025)","0","pure_quanta_power","I72";
;
HDL_POWER"PVDDCR_CPU0_P1"
CDS_LIB"pure_quanta_power";
"A"30;
%"ISL99390FRZTR5935"
"1","(-5675,1575)","0","pure_quanta","I9";
;
LOCATION"PU28"
$SEC"1"
CDS_SEC"1"
MATERIAL"IC"
VALUE"ISL99390FRZ-TR5935"
PART_TYPE"SMLF"
NEEDS_NO_SIZE"TRUE"
CDS_LMAN_SYM_OUTLINE"-300,700,250,-650"
CDS_LIB"pure_quanta"
PART_NUMBER"AL099390004";
"PGND2"
$PN"7_9-20_24"21;
"GL2"
$PN"41"48;
"GL1"
$PN"6"49;
"DNC"
$PN"31"53;
"EN"
$PN"35"50;
"PGND3"
$PN"40"21;
"VOS"
$PN"1"47;
"VIN2"
$PN"30"11;
"PGND1"
$PN"5"21;
"SW"
$PN"10_19"32;
"LSET"
$PN"37"52;
"IOUT"
$PN"38"54;
"TOUT_FLT"
$PN"36"51;
"PVCC"
$PN"4"20;
"PHASE"
$PN"32"31;
"VIN1"
$PN"25_29"11;
"BOOT"
$PN"33"18;
"AGND"
$PN"2"21;
"VCC"
$PN"3"50;
"REFIN"
$PN"39"56;
"PWM"
$PN"34"55;
END.
